# S9S_MB_2U (Grand Teton) — schematic netlist excerpt (pin names and nets, part order shuffled) for the footprints in the layout excerpt that follows; sources: Cadence DE-HDL packaged netlist, KiCad conversion of 03242023_DA0F0TMBIJ0_F0T_Motherboard_J_brd_V01_OCP.brd

ME12  ME_DUMMY_SYMBOL  PICKUP_SMDC20 EMPTY  pkg PICKUP_SMDC20  page 312
R4123  Q_RES  54.9K 1% EMPTY  pkg 0402LF  page 146 : A = P3V3_AUX ; B = GPU_3V3IO_RSVD1_FFU
R1961  Q_RES  10K 1% CHIP  pkg 0402LF  page 202 : A = PGPPA_AUX ; B = ESPI_LFRAME_N_BMC_CS0_N

(kicad_pcb
	(version 20260206)
	(generator "pcbnew")
	(generator_version "10.0")
	(general
		(thickness 1.6)
		(legacy_teardrops no)
	)
	(paper "A4")
	(title_block
		(title "03242023_DA0F0TMBIJ0_F0T_Motherboard_J_brd_V01_OCP.brd")
		(comment 1 "Grand Teton / footprints 1176-1178 of 6105")
	)
	(layers
		(0 "F.Cu" signal "TOP")
		(4 "In1.Cu" signal "GND")
		(6 "In2.Cu" signal "IN1")
		(8 "In3.Cu" signal "GND1")
		(10 "In4.Cu" signal "IN2")
		(12 "In5.Cu" signal "GND2")
		(14 "In6.Cu" signal "IN3")
		(16 "In7.Cu" signal "GND3")
		(18 "In8.Cu" signal "VCC")
		(20 "In9.Cu" signal "VCC1")
		(22 "In10.Cu" signal "GND4")
		(24 "In11.Cu" signal "IN4")
		(26 "In12.Cu" signal "GND5")
		(28 "In13.Cu" signal "IN5")
		(30 "In14.Cu" signal "GND6")
		(32 "In15.Cu" signal "IN6")
		(34 "In16.Cu" signal "GND7")
		(2 "B.Cu" signal "BOTTOM")
		(9 "F.Adhes" user "F.Adhesive")
		(11 "B.Adhes" user "B.Adhesive")
		(13 "F.Paste" user "Package Geometry/Pastemask Top")
		(15 "B.Paste" user "Package Geometry/Pastemask Bottom")
		(5 "F.SilkS" user "Ref Des/Silkscreen Top")
		(7 "B.SilkS" user "Ref Des/Silkscreen Bottom")
		(1 "F.Mask" user "Board Geometry/Soldermask Top")
		(3 "B.Mask" user "Board Geometry/Soldermask Bottom")
		(17 "Dwgs.User" user "User.Drawings")
		(19 "Cmts.User" user "User.Comments")
		(21 "Eco1.User" user "User.Eco1")
		(23 "Eco2.User" user "User.Eco2")
		(25 "Edge.Cuts" user "Board Geometry/Outline")
		(27 "Margin" user)
		(31 "F.CrtYd" user "Package Geometry/Place Bound Top")
		(29 "B.CrtYd" user "Package Geometry/Place Bound Bottom")
		(35 "F.Fab" user "Ref Des/Assembly Top")
		(33 "B.Fab" user "Ref Des/Assembly Bottom")
	)
	(footprint ""
		(layer "F.Cu")
		(at 336.018124 -26.856182 -90)
		(property "Reference" "R1961"
			(at 0 0 270)
			(layer "F.SilkS")
			(hide yes)
			(effects
				(font
					(size 1.27 1.27)
				)
			)
		)
		(property "Value" ""
			(at 0 0 270)
			(layer "F.Fab")
			(effects
				(font
					(size 1.27 1.27)
				)
			)
		)
		(duplicate_pad_numbers_are_jumpers no)
		(fp_line
			(start -0.7874 0.4064)
			(end -0.7874 -0.4064)
			(stroke
				(width 0.1524)
				(type default)
			)
			(layer "F.SilkS")
		)
		(fp_line
			(start 0.7874 0.4064)
			(end -0.7874 0.4064)
			(stroke
				(width 0.1524)
				(type default)
			)
			(layer "F.SilkS")
		)
		(fp_line
			(start -0.7874 -0.4064)
			(end 0.7874 -0.4064)
			(stroke
				(width 0.1524)
				(type default)
			)
			(layer "F.SilkS")
		)
		(fp_line
			(start 0.7874 -0.4064)
			(end 0.7874 0.4064)
			(stroke
				(width 0.1524)
				(type default)
			)
			(layer "F.SilkS")
		)
		(fp_line
			(start -0.67945 0.3048)
			(end -0.67945 -0.305054)
			(stroke
				(width 0.1)
				(type default)
			)
			(layer "F.Fab")
		)
		(fp_line
			(start -0.12065 0.3048)
			(end -0.67945 0.3048)
			(stroke
				(width 0.1)
				(type default)
			)
			(layer "F.Fab")
		)
		(fp_line
			(start 0.120396 0.3048)
			(end 0.120396 0.2794)
			(stroke
				(width 0.1)
				(type default)
			)
			(layer "F.Fab")
		)
		(fp_line
			(start 0.67945 0.3048)
			(end 0.120396 0.3048)
			(stroke
				(width 0.1)
				(type default)
			)
			(layer "F.Fab")
		)
		(fp_line
			(start -0.12065 0.2794)
			(end -0.12065 0.3048)
			(stroke
				(width 0.1)
				(type default)
			)
			(layer "F.Fab")
		)
		(fp_line
			(start 0.120396 0.2794)
			(end -0.12065 0.2794)
			(stroke
				(width 0.1)
				(type default)
			)
			(layer "F.Fab")
		)
		(fp_line
			(start -0.12065 -0.2794)
			(end 0.12065 -0.2794)
			(stroke
				(width 0.1)
				(type default)
			)
			(layer "F.Fab")
		)
		(fp_line
			(start 0.12065 -0.2794)
			(end 0.12065 -0.3048)
			(stroke
				(width 0.1)
				(type default)
			)
			(layer "F.Fab")
		)
		(fp_line
			(start 0.12065 -0.3048)
			(end 0.67945 -0.3048)
			(stroke
				(width 0.1)
				(type default)
			)
			(layer "F.Fab")
		)
		(fp_line
			(start 0.67945 -0.3048)
			(end 0.67945 0.3048)
			(stroke
				(width 0.1)
				(type default)
			)
			(layer "F.Fab")
		)
		(fp_line
			(start -0.67945 -0.305054)
			(end -0.12065 -0.305054)
			(stroke
				(width 0.1)
				(type default)
			)
			(layer "F.Fab")
		)
		(fp_line
			(start -0.12065 -0.305054)
			(end -0.12065 -0.2794)
			(stroke
				(width 0.1)
				(type default)
			)
			(layer "F.Fab")
		)
		(pad "1" smd circle
			(at -0.40005 0 270)
			(size 0 0)
			(layers "F.Cu" "F.Mask" "F.Paste")
			(net "PGPPA_AUX")
		)
		(pad "2" smd circle
			(at 0.40005 0 270)
			(size 0 0)
			(layers "F.Cu" "F.Mask" "F.Paste")
			(net "ESPI_LFRAME_N_BMC_CS0_N")
		)
	)
	(footprint ""
		(layer "F.Cu")
		(at 65.52946 -379.03912)
		(property "Reference" "ME12"
			(at -9.652 -9.540748 0)
			(unlocked yes)
			(layer "F.SilkS")
			(effects
				(font
					(size 0.7874 0.5842)
					(thickness 0.1524)
				)
				(justify left)
			)
		)
		(property "Value" ""
			(at 0 0 0)
			(layer "F.Fab")
			(effects
				(font
					(size 1.27 1.27)
				)
			)
		)
		(duplicate_pad_numbers_are_jumpers no)
		(zone
			(layer "F.Cu")
			(hatch none 0.5)
			(connect_pads
				(clearance 0)
			)
			(min_thickness 0.25)
			(keepout
				(tracks allowed)
				(vias allowed)
				(pads allowed)
				(copperpour allowed)
				(footprints not_allowed)
			)
			(placement
				(enabled no)
				(sheetname "")
			)
			(fill
				(thermal_gap 0.5)
				(thermal_bridge_width 0.5)
				(island_removal_mode 0)
			)
			(polygon
				(pts
					(arc
						(start 75.52944 -379.03912)
						(mid 55.52948 -379.03912)
						(end 75.52944 -379.03912)
					)
				)
			)
		)
	)
	(footprint ""
		(layer "F.Cu")
		(at 308.33314 -433.12461 90)
		(property "Reference" "R4123"
			(at 0 0 90)
			(layer "F.SilkS")
			(hide yes)
			(effects
				(font
					(size 1.27 1.27)
				)
			)
		)
		(property "Value" ""
			(at 0 0 90)
			(layer "F.Fab")
			(effects
				(font
					(size 1.27 1.27)
				)
			)
		)
		(duplicate_pad_numbers_are_jumpers no)
		(fp_line
			(start 0.7874 -0.4064)
			(end 0.7874 0.4064)
			(stroke
				(width 0.1524)
				(type default)
			)
			(layer "F.SilkS")
		)
		(fp_line
			(start -0.7874 -0.4064)
			(end 0.7874 -0.4064)
			(stroke
				(width 0.1524)
				(type default)
			)
			(layer "F.SilkS")
		)
		(fp_line
			(start 0.7874 0.4064)
			(end -0.7874 0.4064)
			(stroke
				(width 0.1524)
				(type default)
			)
			(layer "F.SilkS")
		)
		(fp_line
			(start -0.7874 0.4064)
			(end -0.7874 -0.4064)
			(stroke
				(width 0.1524)
				(type default)
			)
			(layer "F.SilkS")
		)
		(fp_line
			(start -0.12065 -0.305054)
			(end -0.12065 -0.2794)
			(stroke
				(width 0.1)
				(type default)
			)
			(layer "F.Fab")
		)
		(fp_line
			(start -0.67945 -0.305054)
			(end -0.12065 -0.305054)
			(stroke
				(width 0.1)
				(type default)
			)
			(layer "F.Fab")
		)
		(fp_line
			(start 0.67945 -0.3048)
			(end 0.67945 0.3048)
			(stroke
				(width 0.1)
				(type default)
			)
			(layer "F.Fab")
		)
		(fp_line
			(start 0.12065 -0.3048)
			(end 0.67945 -0.3048)
			(stroke
				(width 0.1)
				(type default)
			)
			(layer "F.Fab")
		)
		(fp_line
			(start 0.12065 -0.2794)
			(end 0.12065 -0.3048)
			(stroke
				(width 0.1)
				(type default)
			)
			(layer "F.Fab")
		)
		(fp_line
			(start -0.12065 -0.2794)
			(end 0.12065 -0.2794)
			(stroke
				(width 0.1)
				(type default)
			)
			(layer "F.Fab")
		)
		(fp_line
			(start 0.120396 0.2794)
			(end -0.12065 0.2794)
			(stroke
				(width 0.1)
				(type default)
			)
			(layer "F.Fab")
		)
		(fp_line
			(start -0.12065 0.2794)
			(end -0.12065 0.3048)
			(stroke
				(width 0.1)
				(type default)
			)
			(layer "F.Fab")
		)
		(fp_line
			(start 0.67945 0.3048)
			(end 0.120396 0.3048)
			(stroke
				(width 0.1)
				(type default)
			)
			(layer "F.Fab")
		)
		(fp_line
			(start 0.120396 0.3048)
			(end 0.120396 0.2794)
			(stroke
				(width 0.1)
				(type default)
			)
			(layer "F.Fab")
		)
		(fp_line
			(start -0.12065 0.3048)
			(end -0.67945 0.3048)
			(stroke
				(width 0.1)
				(type default)
			)
			(layer "F.Fab")
		)
		(fp_line
			(start -0.67945 0.3048)
			(end -0.67945 -0.305054)
			(stroke
				(width 0.1)
				(type default)
			)
			(layer "F.Fab")
		)
		(pad "1" smd circle
			(at -0.40005 0 90)
			(size 0 0)
			(layers "F.Cu" "F.Mask" "F.Paste")
			(net "P3V3_AUX")
		)
		(pad "2" smd circle
			(at 0.40005 0 90)
			(size 0 0)
			(layers "F.Cu" "F.Mask" "F.Paste")
			(net "GPU_3V3IO_RSVD1_FFU")
		)
	)
)
